(kicad_pcb
	(version 20260206)
	(generator "pcbnew")
	(generator_version "10.0")
	(general
		(thickness 1.6)
		(legacy_teardrops no)
	)
	(paper "A4")
	(title_block
		(title "04192023_DAF0TMB3IC0_F0TG_MB_C_brd_V02_OCP.brd")
		(comment 1 "Grand Teton / footprints 7625-7632 of 8354")
	)
	(layers
		(0 "F.Cu" signal "TOP")
		(4 "In1.Cu" signal "GND")
		(6 "In2.Cu" signal "IN1")
		(8 "In3.Cu" signal "GND1")
		(10 "In4.Cu" signal "IN2")
		(12 "In5.Cu" signal "GND2")
		(14 "In6.Cu" signal "IN3")
		(16 "In7.Cu" signal "GND3")
		(18 "In8.Cu" signal "VCC")
		(20 "In9.Cu" signal "VCC1")
		(22 "In10.Cu" signal "GND4")
		(24 "In11.Cu" signal "IN4")
		(26 "In12.Cu" signal "GND5")
		(28 "In13.Cu" signal "IN5")
		(30 "In14.Cu" signal "GND6")
		(32 "In15.Cu" signal "IN6")
		(34 "In16.Cu" signal "GND7")
		(2 "B.Cu" signal "BOTTOM")
		(9 "F.Adhes" user "F.Adhesive")
		(11 "B.Adhes" user "B.Adhesive")
		(13 "F.Paste" user "Package Geometry/Pastemask Top")
		(15 "B.Paste" user "Package Geometry/Pastemask Bottom")
		(5 "F.SilkS" user "Ref Des/Silkscreen Top")
		(7 "B.SilkS" user "Ref Des/Silkscreen Bottom")
		(1 "F.Mask" user "Board Geometry/Soldermask Top")
		(3 "B.Mask" user "Board Geometry/Soldermask Bottom")
		(17 "Dwgs.User" user "User.Drawings")
		(19 "Cmts.User" user "User.Comments")
		(21 "Eco1.User" user "User.Eco1")
		(23 "Eco2.User" user "User.Eco2")
		(25 "Edge.Cuts" user "Board Geometry/Outline")
		(27 "Margin" user)
		(31 "F.CrtYd" user "Package Geometry/Place Bound Top")
		(29 "B.CrtYd" user "Package Geometry/Place Bound Bottom")
		(35 "F.Fab" user "Ref Des/Assembly Top")
		(33 "B.Fab" user "Ref Des/Assembly Bottom")
	)
	(footprint ""
		(layer "B.Cu")
		(at 127.678434 -386.766562 90)
		(property "Reference" "C460"
			(at 0 0 90)
			(layer "B.SilkS")
			(hide yes)
			(effects
				(font
					(size 1.27 1.27)
				)
				(justify mirror)
			)
		)
		(property "Value" ""
			(at 0 0 90)
			(layer "B.Fab")
			(effects
				(font
					(size 1.27 1.27)
				)
				(justify mirror)
			)
		)
		(duplicate_pad_numbers_are_jumpers no)
		(fp_line
			(start 0.299974 -0.150114)
			(end -0.299974 -0.150114)
			(stroke
				(width 0.1)
				(type default)
			)
			(layer "B.Fab")
		)
		(fp_line
			(start -0.299974 -0.150114)
			(end -0.299974 0.150114)
			(stroke
				(width 0.1)
				(type default)
			)
			(layer "B.Fab")
		)
		(fp_line
			(start 0.299974 0.150114)
			(end 0.299974 -0.150114)
			(stroke
				(width 0.1)
				(type default)
			)
			(layer "B.Fab")
		)
		(fp_line
			(start -0.299974 0.150114)
			(end 0.299974 0.150114)
			(stroke
				(width 0.1)
				(type default)
			)
			(layer "B.Fab")
		)
		(pad "1" smd rect
			(at 0.2667 0 270)
			(size 0.3048 0.381)
			(layers "B.Cu" "B.Mask" "B.Paste")
			(net "P0V9_CPU1_RT3_2A_2D")
		)
		(pad "2" smd rect
			(at -0.2667 0 270)
			(size 0.3048 0.381)
			(layers "B.Cu" "B.Mask" "B.Paste")
			(net "GND")
		)
	)
	(footprint ""
		(layer "B.Cu")
		(at 181.182518 -415.616644 -90)
		(property "Reference" "R2911"
			(at 0 0 90)
			(layer "B.SilkS")
			(hide yes)
			(effects
				(font
					(size 1.27 1.27)
				)
				(justify mirror)
			)
		)
		(property "Value" ""
			(at 0 0 90)
			(layer "B.Fab")
			(effects
				(font
					(size 1.27 1.27)
				)
				(justify mirror)
			)
		)
		(duplicate_pad_numbers_are_jumpers no)
		(fp_line
			(start -0.7874 0.4064)
			(end 0.7874 0.4064)
			(stroke
				(width 0.1524)
				(type default)
			)
			(layer "B.SilkS")
		)
		(fp_line
			(start 0.7874 0.4064)
			(end 0.7874 -0.4064)
			(stroke
				(width 0.1524)
				(type default)
			)
			(layer "B.SilkS")
		)
		(fp_line
			(start -0.7874 -0.4064)
			(end -0.7874 0.4064)
			(stroke
				(width 0.1524)
				(type default)
			)
			(layer "B.SilkS")
		)
		(fp_line
			(start 0.7874 -0.4064)
			(end -0.7874 -0.4064)
			(stroke
				(width 0.1524)
				(type default)
			)
			(layer "B.SilkS")
		)
		(fp_line
			(start -0.67945 0.3048)
			(end -0.120396 0.3048)
			(stroke
				(width 0.1)
				(type default)
			)
			(layer "B.Fab")
		)
		(fp_line
			(start -0.120396 0.3048)
			(end -0.120396 0.2794)
			(stroke
				(width 0.1)
				(type default)
			)
			(layer "B.Fab")
		)
		(fp_line
			(start 0.12065 0.3048)
			(end 0.67945 0.3048)
			(stroke
				(width 0.1)
				(type default)
			)
			(layer "B.Fab")
		)
		(fp_line
			(start 0.67945 0.3048)
			(end 0.67945 -0.305054)
			(stroke
				(width 0.1)
				(type default)
			)
			(layer "B.Fab")
		)
		(fp_line
			(start -0.120396 0.2794)
			(end 0.12065 0.2794)
			(stroke
				(width 0.1)
				(type default)
			)
			(layer "B.Fab")
		)
		(fp_line
			(start 0.12065 0.2794)
			(end 0.12065 0.3048)
			(stroke
				(width 0.1)
				(type default)
			)
			(layer "B.Fab")
		)
		(fp_line
			(start -0.12065 -0.2794)
			(end -0.12065 -0.3048)
			(stroke
				(width 0.1)
				(type default)
			)
			(layer "B.Fab")
		)
		(fp_line
			(start 0.12065 -0.2794)
			(end -0.12065 -0.2794)
			(stroke
				(width 0.1)
				(type default)
			)
			(layer "B.Fab")
		)
		(fp_line
			(start -0.67945 -0.3048)
			(end -0.67945 0.3048)
			(stroke
				(width 0.1)
				(type default)
			)
			(layer "B.Fab")
		)
		(fp_line
			(start -0.12065 -0.3048)
			(end -0.67945 -0.3048)
			(stroke
				(width 0.1)
				(type default)
			)
			(layer "B.Fab")
		)
		(fp_line
			(start 0.12065 -0.305054)
			(end 0.12065 -0.2794)
			(stroke
				(width 0.1)
				(type default)
			)
			(layer "B.Fab")
		)
		(fp_line
			(start 0.67945 -0.305054)
			(end 0.12065 -0.305054)
			(stroke
				(width 0.1)
				(type default)
			)
			(layer "B.Fab")
		)
		(pad "1" smd circle
			(at 0.40005 0 90)
			(size 0 0)
			(layers "B.Cu" "B.Mask" "B.Paste")
			(net "P3V3_AUX")
		)
		(pad "2" smd circle
			(at -0.40005 0 90)
			(size 0 0)
			(layers "B.Cu" "B.Mask" "B.Paste")
			(net "RST_SWB_BIC_BUF_R_N")
		)
	)
	(footprint ""
		(layer "B.Cu")
		(at 231.143048 -322.84035)
		(property "Reference" "R1259"
			(at 0 0 0)
			(layer "B.SilkS")
			(hide yes)
			(effects
				(font
					(size 1.27 1.27)
				)
				(justify mirror)
			)
		)
		(property "Value" ""
			(at 0 0 0)
			(layer "B.Fab")
			(effects
				(font
					(size 1.27 1.27)
				)
				(justify mirror)
			)
		)
		(duplicate_pad_numbers_are_jumpers no)
		(fp_line
			(start -0.7874 -0.4064)
			(end -0.7874 0.4064)
			(stroke
				(width 0.1524)
				(type default)
			)
			(layer "B.SilkS")
		)
		(fp_line
			(start -0.7874 0.4064)
			(end 0.7874 0.4064)
			(stroke
				(width 0.1524)
				(type default)
			)
			(layer "B.SilkS")
		)
		(fp_line
			(start 0.7874 -0.4064)
			(end -0.7874 -0.4064)
			(stroke
				(width 0.1524)
				(type default)
			)
			(layer "B.SilkS")
		)
		(fp_line
			(start 0.7874 0.4064)
			(end 0.7874 -0.4064)
			(stroke
				(width 0.1524)
				(type default)
			)
			(layer "B.SilkS")
		)
		(fp_line
			(start -0.67945 -0.3048)
			(end -0.67945 0.3048)
			(stroke
				(width 0.1)
				(type default)
			)
			(layer "B.Fab")
		)
		(fp_line
			(start -0.67945 0.3048)
			(end -0.120396 0.3048)
			(stroke
				(width 0.1)
				(type default)
			)
			(layer "B.Fab")
		)
		(fp_line
			(start -0.12065 -0.3048)
			(end -0.67945 -0.3048)
			(stroke
				(width 0.1)
				(type default)
			)
			(layer "B.Fab")
		)
		(fp_line
			(start -0.12065 -0.2794)
			(end -0.12065 -0.3048)
			(stroke
				(width 0.1)
				(type default)
			)
			(layer "B.Fab")
		)
		(fp_line
			(start -0.120396 0.2794)
			(end 0.12065 0.2794)
			(stroke
				(width 0.1)
				(type default)
			)
			(layer "B.Fab")
		)
		(fp_line
			(start -0.120396 0.3048)
			(end -0.120396 0.2794)
			(stroke
				(width 0.1)
				(type default)
			)
			(layer "B.Fab")
		)
		(fp_line
			(start 0.12065 -0.305054)
			(end 0.12065 -0.2794)
			(stroke
				(width 0.1)
				(type default)
			)
			(layer "B.Fab")
		)
		(fp_line
			(start 0.12065 -0.2794)
			(end -0.12065 -0.2794)
			(stroke
				(width 0.1)
				(type default)
			)
			(layer "B.Fab")
		)
		(fp_line
			(start 0.12065 0.2794)
			(end 0.12065 0.3048)
			(stroke
				(width 0.1)
				(type default)
			)
			(layer "B.Fab")
		)
		(fp_line
			(start 0.12065 0.3048)
			(end 0.67945 0.3048)
			(stroke
				(width 0.1)
				(type default)
			)
			(layer "B.Fab")
		)
		(fp_line
			(start 0.67945 -0.305054)
			(end 0.12065 -0.305054)
			(stroke
				(width 0.1)
				(type default)
			)
			(layer "B.Fab")
		)
		(fp_line
			(start 0.67945 0.3048)
			(end 0.67945 -0.305054)
			(stroke
				(width 0.1)
				(type default)
			)
			(layer "B.Fab")
		)
		(pad "1" smd rect
			(at 0.40005 0)
			(size 0.4572 0.508)
			(layers "B.Cu" "B.Mask" "B.Paste")
			(net "P1V8_AUX_ADC")
		)
		(pad "2" smd rect
			(at -0.40005 0)
			(size 0.4572 0.508)
			(layers "B.Cu" "B.Mask" "B.Paste")
			(net "P1V8_AUX_ADC_TIC")
		)
	)
	(footprint ""
		(layer "B.Cu")
		(at 114.439954 -168.142412 90)
		(property "Reference" "PC327_1"
			(at 0 0 90)
			(layer "B.SilkS")
			(hide yes)
			(effects
				(font
					(size 1.27 1.27)
				)
				(justify mirror)
			)
		)
		(property "Value" ""
			(at 0 0 90)
			(layer "B.Fab")
			(effects
				(font
					(size 1.27 1.27)
				)
				(justify mirror)
			)
		)
		(duplicate_pad_numbers_are_jumpers no)
		(fp_line
			(start 1.524 -0.762)
			(end -1.524 -0.762)
			(stroke
				(width 0.1524)
				(type default)
			)
			(layer "B.SilkS")
		)
		(fp_line
			(start -1.524 -0.762)
			(end -1.524 0.762)
			(stroke
				(width 0.1524)
				(type default)
			)
			(layer "B.SilkS")
		)
		(fp_line
			(start 1.524 0.762)
			(end 1.524 -0.762)
			(stroke
				(width 0.1524)
				(type default)
			)
			(layer "B.SilkS")
		)
		(fp_line
			(start -1.524 0.762)
			(end 1.524 0.762)
			(stroke
				(width 0.1524)
				(type default)
			)
			(layer "B.SilkS")
		)
		(fp_line
			(start 1.1049 -0.724916)
			(end 1.1049 0.724916)
			(stroke
				(width 0.1)
				(type default)
			)
			(layer "B.Fab")
		)
		(fp_line
			(start -1.1049 -0.724916)
			(end 1.1049 -0.724916)
			(stroke
				(width 0.1)
				(type default)
			)
			(layer "B.Fab")
		)
		(fp_line
			(start 1.1049 0.724916)
			(end -1.1049 0.724916)
			(stroke
				(width 0.1)
				(type default)
			)
			(layer "B.Fab")
		)
		(fp_line
			(start -1.1049 0.724916)
			(end -1.1049 -0.724916)
			(stroke
				(width 0.1)
				(type default)
			)
			(layer "B.Fab")
		)
		(pad "1" smd rect
			(at 0.889 0 90)
			(size 1.016 1.27)
			(layers "B.Cu" "B.Mask" "B.Paste")
			(net "SW_P12V_AUX_PVDDCR_SOC_P1_FLT")
		)
		(pad "2" smd rect
			(at -0.889 0 90)
			(size 1.016 1.27)
			(layers "B.Cu" "B.Mask" "B.Paste")
			(net "GND")
		)
	)
	(footprint ""
		(layer "B.Cu")
		(at 410.073602 -416.899344 90)
		(property "Reference" "C6621"
			(at 0 0 90)
			(layer "B.SilkS")
			(hide yes)
			(effects
				(font
					(size 1.27 1.27)
				)
				(justify mirror)
			)
		)
		(property "Value" ""
			(at 0 0 90)
			(layer "B.Fab")
			(effects
				(font
					(size 1.27 1.27)
				)
				(justify mirror)
			)
		)
		(duplicate_pad_numbers_are_jumpers no)
		(fp_line
			(start 0.299974 -0.150114)
			(end -0.299974 -0.150114)
			(stroke
				(width 0.1)
				(type default)
			)
			(layer "B.Fab")
		)
		(fp_line
			(start -0.299974 -0.150114)
			(end -0.299974 0.150114)
			(stroke
				(width 0.1)
				(type default)
			)
			(layer "B.Fab")
		)
		(fp_line
			(start 0.299974 0.150114)
			(end 0.299974 -0.150114)
			(stroke
				(width 0.1)
				(type default)
			)
			(layer "B.Fab")
		)
		(fp_line
			(start -0.299974 0.150114)
			(end 0.299974 0.150114)
			(stroke
				(width 0.1)
				(type default)
			)
			(layer "B.Fab")
		)
		(pad "1" smd rect
			(at 0.2667 0 270)
			(size 0.3048 0.381)
			(layers "B.Cu" "B.Mask" "B.Paste")
			(net "P5E_CPU0_P3_TX_BUF_C_DP<12>")
		)
		(pad "2" smd rect
			(at -0.2667 0 270)
			(size 0.3048 0.381)
			(layers "B.Cu" "B.Mask" "B.Paste")
			(net "P5E_CPU0_P3_TX_BUF_DP<12>")
		)
	)
	(footprint ""
		(layer "B.Cu")
		(at 474.29293 -212.746082)
		(property "Reference" "DB14"
			(at 2.639822 -5.63118 270)
			(unlocked yes)
			(layer "B.SilkS")
			(effects
				(font
					(size 0.7874 0.5842)
					(thickness 0.1524)
				)
				(justify left mirror)
			)
		)
		(property "Value" ""
			(at 0 0 0)
			(layer "B.Fab")
			(effects
				(font
					(size 1.27 1.27)
				)
				(justify mirror)
			)
		)
		(duplicate_pad_numbers_are_jumpers no)
		(fp_line
			(start -3.330702 -4.771136)
			(end 0 4.011168)
			(stroke
				(width 0.1524)
				(type default)
			)
			(layer "B.SilkS")
		)
		(fp_line
			(start 0 4.011168)
			(end 3.330702 -4.771136)
			(stroke
				(width 0.1524)
				(type default)
			)
			(layer "B.SilkS")
		)
		(fp_line
			(start 3.330702 -4.771136)
			(end -3.330702 -4.771136)
			(stroke
				(width 0.1524)
				(type default)
			)
			(layer "B.SilkS")
		)
		(fp_line
			(start -3.330702 -4.771136)
			(end 0 4.011168)
			(stroke
				(width 0.1)
				(type default)
			)
			(layer "B.Fab")
		)
		(fp_line
			(start 0 4.011168)
			(end 3.330702 -4.771136)
			(stroke
				(width 0.1)
				(type default)
			)
			(layer "B.Fab")
		)
		(fp_line
			(start 3.330702 -4.771136)
			(end -3.330702 -4.771136)
			(stroke
				(width 0.1)
				(type default)
			)
			(layer "B.Fab")
		)
		(pad "1" thru_hole circle
			(at 0 0 180)
			(size 2.159 2.159)
			(drill 1.7018)
			(layers "*.Cu" "*.Mask")
			(remove_unused_layers no)
			(net "T1_GND")
			(clearance 0.0254)
			(thermal_gap 0.0254)
		)
		(pad "2" thru_hole circle
			(at 1.27 -3.348736 180)
			(size 2.159 2.159)
			(drill 1.7018)
			(layers "*.Cu" "*.Mask")
			(remove_unused_layers no)
			(net "TDR_SE_45_OHM_IN6")
			(clearance 0.0254)
			(thermal_gap 0.0254)
		)
		(pad "3" thru_hole circle
			(at -1.27 -3.348736 180)
			(size 2.159 2.159)
			(drill 1.7018)
			(layers "*.Cu" "*.Mask")
			(remove_unused_layers no)
			(net "TDR_SE_45_OHM_IN6")
			(clearance 0.0254)
			(thermal_gap 0.0254)
		)
	)
	(footprint ""
		(layer "B.Cu")
		(at 409.809188 -165.928548 90)
		(property "Reference" "PR363"
			(at 0 0 90)
			(layer "B.SilkS")
			(hide yes)
			(effects
				(font
					(size 1.27 1.27)
				)
				(justify mirror)
			)
		)
		(property "Value" ""
			(at 0 0 90)
			(layer "B.Fab")
			(effects
				(font
					(size 1.27 1.27)
				)
				(justify mirror)
			)
		)
		(duplicate_pad_numbers_are_jumpers no)
		(fp_line
			(start 0.7874 -0.4064)
			(end -0.7874 -0.4064)
			(stroke
				(width 0.1524)
				(type default)
			)
			(layer "B.SilkS")
		)
		(fp_line
			(start -0.7874 -0.4064)
			(end -0.7874 0.4064)
			(stroke
				(width 0.1524)
				(type default)
			)
			(layer "B.SilkS")
		)
		(fp_line
			(start 0.7874 0.4064)
			(end 0.7874 -0.4064)
			(stroke
				(width 0.1524)
				(type default)
			)
			(layer "B.SilkS")
		)
		(fp_line
			(start -0.7874 0.4064)
			(end 0.7874 0.4064)
			(stroke
				(width 0.1524)
				(type default)
			)
			(layer "B.SilkS")
		)
		(fp_line
			(start 0.67945 -0.305054)
			(end 0.12065 -0.305054)
			(stroke
				(width 0.1)
				(type default)
			)
			(layer "B.Fab")
		)
		(fp_line
			(start 0.12065 -0.305054)
			(end 0.12065 -0.2794)
			(stroke
				(width 0.1)
				(type default)
			)
			(layer "B.Fab")
		)
		(fp_line
			(start -0.12065 -0.3048)
			(end -0.67945 -0.3048)
			(stroke
				(width 0.1)
				(type default)
			)
			(layer "B.Fab")
		)
		(fp_line
			(start -0.67945 -0.3048)
			(end -0.67945 0.3048)
			(stroke
				(width 0.1)
				(type default)
			)
			(layer "B.Fab")
		)
		(fp_line
			(start 0.12065 -0.2794)
			(end -0.12065 -0.2794)
			(stroke
				(width 0.1)
				(type default)
			)
			(layer "B.Fab")
		)
		(fp_line
			(start -0.12065 -0.2794)
			(end -0.12065 -0.3048)
			(stroke
				(width 0.1)
				(type default)
			)
			(layer "B.Fab")
		)
		(fp_line
			(start 0.12065 0.2794)
			(end 0.12065 0.3048)
			(stroke
				(width 0.1)
				(type default)
			)
			(layer "B.Fab")
		)
		(fp_line
			(start -0.120396 0.2794)
			(end 0.12065 0.2794)
			(stroke
				(width 0.1)
				(type default)
			)
			(layer "B.Fab")
		)
		(fp_line
			(start 0.67945 0.3048)
			(end 0.67945 -0.305054)
			(stroke
				(width 0.1)
				(type default)
			)
			(layer "B.Fab")
		)
		(fp_line
			(start 0.12065 0.3048)
			(end 0.67945 0.3048)
			(stroke
				(width 0.1)
				(type default)
			)
			(layer "B.Fab")
		)
		(fp_line
			(start -0.120396 0.3048)
			(end -0.120396 0.2794)
			(stroke
				(width 0.1)
				(type default)
			)
			(layer "B.Fab")
		)
		(fp_line
			(start -0.67945 0.3048)
			(end -0.120396 0.3048)
			(stroke
				(width 0.1)
				(type default)
			)
			(layer "B.Fab")
		)
		(pad "1" smd circle
			(at 0.40005 0 270)
			(size 0 0)
			(layers "B.Cu" "B.Mask" "B.Paste")
			(net "PVDDCR_SOC_P0_VOS2")
		)
		(pad "2" smd circle
			(at -0.40005 0 270)
			(size 0 0)
			(layers "B.Cu" "B.Mask" "B.Paste")
			(net "PVDDCR_SOC_P0")
		)
	)
	(footprint ""
		(layer "B.Cu")
		(at 187.35294 -130.468116 -90)
		(property "Reference" "R193"
			(at 0 0 90)
			(layer "B.SilkS")
			(hide yes)
			(effects
				(font
					(size 1.27 1.27)
				)
				(justify mirror)
			)
		)
		(property "Value" ""
			(at 0 0 90)
			(layer "B.Fab")
			(effects
				(font
					(size 1.27 1.27)
				)
				(justify mirror)
			)
		)
		(duplicate_pad_numbers_are_jumpers no)
		(fp_line
			(start -0.7874 0.4064)
			(end 0.7874 0.4064)
			(stroke
				(width 0.1524)
				(type default)
			)
			(layer "B.SilkS")
		)
		(fp_line
			(start 0.7874 0.4064)
			(end 0.7874 -0.4064)
			(stroke
				(width 0.1524)
				(type default)
			)
			(layer "B.SilkS")
		)
		(fp_line
			(start -0.7874 -0.4064)
			(end -0.7874 0.4064)
			(stroke
				(width 0.1524)
				(type default)
			)
			(layer "B.SilkS")
		)
		(fp_line
			(start 0.7874 -0.4064)
			(end -0.7874 -0.4064)
			(stroke
				(width 0.1524)
				(type default)
			)
			(layer "B.SilkS")
		)
		(fp_line
			(start -0.67945 0.3048)
			(end -0.120396 0.3048)
			(stroke
				(width 0.1)
				(type default)
			)
			(layer "B.Fab")
		)
		(fp_line
			(start -0.120396 0.3048)
			(end -0.120396 0.2794)
			(stroke
				(width 0.1)
				(type default)
			)
			(layer "B.Fab")
		)
		(fp_line
			(start 0.12065 0.3048)
			(end 0.67945 0.3048)
			(stroke
				(width 0.1)
				(type default)
			)
			(layer "B.Fab")
		)
		(fp_line
			(start 0.67945 0.3048)
			(end 0.67945 -0.305054)
			(stroke
				(width 0.1)
				(type default)
			)
			(layer "B.Fab")
		)
		(fp_line
			(start -0.120396 0.2794)
			(end 0.12065 0.2794)
			(stroke
				(width 0.1)
				(type default)
			)
			(layer "B.Fab")
		)
		(fp_line
			(start 0.12065 0.2794)
			(end 0.12065 0.3048)
			(stroke
				(width 0.1)
				(type default)
			)
			(layer "B.Fab")
		)
		(fp_line
			(start -0.12065 -0.2794)
			(end -0.12065 -0.3048)
			(stroke
				(width 0.1)
				(type default)
			)
			(layer "B.Fab")
		)
		(fp_line
			(start 0.12065 -0.2794)
			(end -0.12065 -0.2794)
			(stroke
				(width 0.1)
				(type default)
			)
			(layer "B.Fab")
		)
		(fp_line
			(start -0.67945 -0.3048)
			(end -0.67945 0.3048)
			(stroke
				(width 0.1)
				(type default)
			)
			(layer "B.Fab")
		)
		(fp_line
			(start -0.12065 -0.3048)
			(end -0.67945 -0.3048)
			(stroke
				(width 0.1)
				(type default)
			)
			(layer "B.Fab")
		)
		(fp_line
			(start 0.12065 -0.305054)
			(end 0.12065 -0.2794)
			(stroke
				(width 0.1)
				(type default)
			)
			(layer "B.Fab")
		)
		(fp_line
			(start 0.67945 -0.305054)
			(end 0.12065 -0.305054)
			(stroke
				(width 0.1)
				(type default)
			)
			(layer "B.Fab")
		)
		(pad "1" smd circle
			(at 0.40005 0 90)
			(size 0 0)
			(layers "B.Cu" "B.Mask" "B.Paste")
			(net "FM_CPU1_SMERR_N")
		)
		(pad "2" smd circle
			(at -0.40005 0 90)
			(size 0 0)
			(layers "B.Cu" "B.Mask" "B.Paste")
			(net "CPU1_SMERR_N")
		)
	)
)
